(kicad_pcb
	(version 20260206)
	(generator "pcbnew")
	(generator_version "10.0")
	(general
		(thickness 1.6)
		(legacy_teardrops no)
	)
	(paper "A4")
	(title_block
		(title "baseboard — 13948-1b.1110WZS1818.brd")
		(comment 1 "Honey Badger (Wiwynn) / footprints 1019-1025 of 2523")
	)
	(layers
		(0 "F.Cu" signal "TOP")
		(4 "In1.Cu" signal "L2GND")
		(6 "In2.Cu" signal "L3")
		(8 "In3.Cu" signal "L4VCC")
		(10 "In4.Cu" signal "L5VCC")
		(12 "In5.Cu" signal "L6")
		(14 "In6.Cu" signal "L7GND")
		(2 "B.Cu" signal "BOTTOM")
		(9 "F.Adhes" user "F.Adhesive")
		(11 "B.Adhes" user "B.Adhesive")
		(13 "F.Paste" user "Package Geometry/Pastemask Top")
		(15 "B.Paste" user "Package Geometry/Pastemask Bottom")
		(5 "F.SilkS" user "Ref Des/Silkscreen Top")
		(7 "B.SilkS" user "Ref Des/Silkscreen Bottom")
		(1 "F.Mask" user "Board Geometry/Soldermask Top")
		(3 "B.Mask" user "Board Geometry/Soldermask Bottom")
		(17 "Dwgs.User" user "User.Drawings")
		(19 "Cmts.User" user "User.Comments")
		(21 "Eco1.User" user "User.Eco1")
		(23 "Eco2.User" user "User.Eco2")
		(25 "Edge.Cuts" user "Board Geometry/Outline")
		(27 "Margin" user)
		(31 "F.CrtYd" user "Package Geometry/Place Bound Top")
		(29 "B.CrtYd" user "Package Geometry/Place Bound Bottom")
		(35 "F.Fab" user "Ref Des/Assembly Top")
		(33 "B.Fab" user "Ref Des/Assembly Bottom")
	)
	(footprint ""
		(layer "F.Cu")
		(at 58.293 -225.806)
		(property "Reference" "R2122"
			(at 0 0 0)
			(layer "F.SilkS")
			(hide yes)
			(effects
				(font
					(size 1.27 1.27)
				)
			)
		)
		(property "Value" "10R2F-L-GP"
			(at 0.064008 -3.993896 0)
			(unlocked yes)
			(layer "F.Fab")
			(hide yes)
			(effects
				(font
					(size 1.016 1.016)
					(thickness 0.1524)
				)
			)
		)
		(property "Device Type" "R402H14"
			(at 0.064008 -5.517896 0)
			(unlocked yes)
			(layer "F.Fab")
			(hide yes)
			(effects
				(font
					(size 1.016 1.016)
					(thickness 0.1524)
				)
			)
		)
		(duplicate_pad_numbers_are_jumpers no)
		(fp_line
			(start -0.508 -0.9398)
			(end -0.508 0.9398)
			(stroke
				(width 0.1524)
				(type default)
			)
			(layer "F.SilkS")
		)
		(fp_line
			(start 0.508 -0.9398)
			(end -0.508 -0.9398)
			(stroke
				(width 0.1524)
				(type default)
			)
			(layer "F.SilkS")
		)
		(fp_rect
			(start -0.508 0.9398)
			(end 0.508 -0.9398)
			(stroke
				(width 0)
				(type default)
			)
			(fill no)
			(layer "F.CrtYd")
		)
		(fp_rect
			(start -0.508 0.9398)
			(end 0.508 -0.9398)
			(stroke
				(width 0)
				(type default)
			)
			(fill no)
			(layer "F.Fab")
		)
		(pad "1" smd custom
			(at 0 -0.4445)
			(size 0.1397 0.1397)
			(layers "F.Cu" "F.Mask" "F.Paste")
			(net "MB0_CM_SENSE_R1_N")
			(options
				(clearance outline)
				(anchor circle)
			)
			(primitives
				(gr_poly
					(pts
						(arc
							(start -0.1778 -0.2794)
							(mid -0.249642 -0.249642)
							(end -0.2794 -0.1778)
						)
						(arc
							(start -0.2794 0.1778)
							(mid -0.249642 0.249642)
							(end -0.1778 0.2794)
						)
						(arc
							(start 0.1778 0.2794)
							(mid 0.249642 0.249642)
							(end 0.2794 0.1778)
						)
						(arc
							(start 0.2794 -0.1778)
							(mid 0.249642 -0.249642)
							(end 0.1778 -0.2794)
						)
					)
					(width 0)
					(fill yes)
				)
			)
		)
		(pad "2" smd custom
			(at 0 0.4445)
			(size 0.1397 0.1397)
			(layers "F.Cu" "F.Mask" "F.Paste")
			(net "MB0_CM_SENSE_N")
			(options
				(clearance outline)
				(anchor circle)
			)
			(primitives
				(gr_poly
					(pts
						(arc
							(start -0.1778 -0.2794)
							(mid -0.249642 -0.249642)
							(end -0.2794 -0.1778)
						)
						(arc
							(start -0.2794 0.1778)
							(mid -0.249642 0.249642)
							(end -0.1778 0.2794)
						)
						(arc
							(start 0.1778 0.2794)
							(mid 0.249642 0.249642)
							(end 0.2794 0.1778)
						)
						(arc
							(start 0.2794 -0.1778)
							(mid 0.249642 -0.249642)
							(end 0.1778 -0.2794)
						)
					)
					(width 0)
					(fill yes)
				)
			)
		)
	)
	(footprint ""
		(layer "F.Cu")
		(at 222.25 -112.395 180)
		(property "Reference" "R605"
			(at 0 0 180)
			(layer "F.SilkS")
			(hide yes)
			(effects
				(font
					(size 1.27 1.27)
				)
			)
		)
		(property "Value" "0R2J-2-GP"
			(at 0.064008 -3.993896 180)
			(unlocked yes)
			(layer "F.Fab")
			(hide yes)
			(effects
				(font
					(size 1.016 1.016)
					(thickness 0.1524)
				)
			)
		)
		(property "Device Type" "R402H16"
			(at 0.064008 -5.517896 180)
			(unlocked yes)
			(layer "F.Fab")
			(hide yes)
			(effects
				(font
					(size 1.016 1.016)
					(thickness 0.1524)
				)
			)
		)
		(duplicate_pad_numbers_are_jumpers no)
		(fp_line
			(start 0.508 -0.9398)
			(end -0.508 -0.9398)
			(stroke
				(width 0.1524)
				(type default)
			)
			(layer "F.SilkS")
		)
		(fp_line
			(start -0.508 -0.9398)
			(end -0.508 0.9398)
			(stroke
				(width 0.1524)
				(type default)
			)
			(layer "F.SilkS")
		)
		(fp_rect
			(start -0.508 0.9398)
			(end 0.508 -0.9398)
			(stroke
				(width 0)
				(type default)
			)
			(fill no)
			(layer "F.CrtYd")
		)
		(fp_rect
			(start -0.508 0.9398)
			(end 0.508 -0.9398)
			(stroke
				(width 0)
				(type default)
			)
			(fill no)
			(layer "F.Fab")
		)
		(pad "1" smd custom
			(at 0 -0.4445 180)
			(size 0.1397 0.1397)
			(layers "F.Cu" "F.Mask" "F.Paste")
			(net "P1V8_C_PG")
			(options
				(clearance outline)
				(anchor circle)
			)
			(primitives
				(gr_poly
					(pts
						(arc
							(start -0.1778 -0.2794)
							(mid -0.249642 -0.249642)
							(end -0.2794 -0.1778)
						)
						(arc
							(start -0.2794 0.1778)
							(mid -0.249642 0.249642)
							(end -0.1778 0.2794)
						)
						(arc
							(start 0.1778 0.2794)
							(mid 0.249642 0.249642)
							(end 0.2794 0.1778)
						)
						(arc
							(start 0.2794 -0.1778)
							(mid 0.249642 -0.249642)
							(end 0.1778 -0.2794)
						)
					)
					(width 0)
					(fill yes)
				)
			)
		)
		(pad "2" smd custom
			(at 0 0.4445 180)
			(size 0.1397 0.1397)
			(layers "F.Cu" "F.Mask" "F.Paste")
			(net "P1V8_PG_R_2")
			(options
				(clearance outline)
				(anchor circle)
			)
			(primitives
				(gr_poly
					(pts
						(arc
							(start -0.1778 -0.2794)
							(mid -0.249642 -0.249642)
							(end -0.2794 -0.1778)
						)
						(arc
							(start -0.2794 0.1778)
							(mid -0.249642 0.249642)
							(end -0.1778 0.2794)
						)
						(arc
							(start 0.1778 0.2794)
							(mid 0.249642 0.249642)
							(end 0.2794 0.1778)
						)
						(arc
							(start 0.2794 -0.1778)
							(mid 0.249642 -0.249642)
							(end 0.1778 -0.2794)
						)
					)
					(width 0)
					(fill yes)
				)
			)
		)
	)
	(footprint ""
		(layer "F.Cu")
		(at 55.89397 -142.24 90)
		(property "Reference" "SR1273"
			(at 0 0 90)
			(layer "F.SilkS")
			(hide yes)
			(effects
				(font
					(size 1.27 1.27)
				)
			)
		)
		(property "Value" "0R2J-2-GP"
			(at 0.064008 -3.993896 90)
			(unlocked yes)
			(layer "F.Fab")
			(hide yes)
			(effects
				(font
					(size 1.016 1.016)
					(thickness 0.1524)
				)
			)
		)
		(property "Device Type" "R402H16"
			(at 0.064008 -5.517896 90)
			(unlocked yes)
			(layer "F.Fab")
			(hide yes)
			(effects
				(font
					(size 1.016 1.016)
					(thickness 0.1524)
				)
			)
		)
		(duplicate_pad_numbers_are_jumpers no)
		(fp_line
			(start 0.508 -0.9398)
			(end -0.508 -0.9398)
			(stroke
				(width 0.1524)
				(type default)
			)
			(layer "F.SilkS")
		)
		(fp_line
			(start -0.508 -0.9398)
			(end -0.508 0.9398)
			(stroke
				(width 0.1524)
				(type default)
			)
			(layer "F.SilkS")
		)
		(fp_rect
			(start -0.508 0.9398)
			(end 0.508 -0.9398)
			(stroke
				(width 0)
				(type default)
			)
			(fill no)
			(layer "F.CrtYd")
		)
		(fp_rect
			(start -0.508 0.9398)
			(end 0.508 -0.9398)
			(stroke
				(width 0)
				(type default)
			)
			(fill no)
			(layer "F.Fab")
		)
		(pad "1" smd custom
			(at 0 -0.4445 90)
			(size 0.1397 0.1397)
			(layers "F.Cu" "F.Mask" "F.Paste")
			(net "RST_BTN_N")
			(options
				(clearance outline)
				(anchor circle)
			)
			(primitives
				(gr_poly
					(pts
						(arc
							(start -0.1778 -0.2794)
							(mid -0.249642 -0.249642)
							(end -0.2794 -0.1778)
						)
						(arc
							(start -0.2794 0.1778)
							(mid -0.249642 0.249642)
							(end -0.1778 0.2794)
						)
						(arc
							(start 0.1778 0.2794)
							(mid 0.249642 0.249642)
							(end 0.2794 0.1778)
						)
						(arc
							(start 0.2794 -0.1778)
							(mid 0.249642 -0.249642)
							(end 0.1778 -0.2794)
						)
					)
					(width 0)
					(fill yes)
				)
			)
		)
		(pad "2" smd custom
			(at 0 0.4445 90)
			(size 0.1397 0.1397)
			(layers "F.Cu" "F.Mask" "F.Paste")
			(net "RST_BTN_R")
			(options
				(clearance outline)
				(anchor circle)
			)
			(primitives
				(gr_poly
					(pts
						(arc
							(start -0.1778 -0.2794)
							(mid -0.249642 -0.249642)
							(end -0.2794 -0.1778)
						)
						(arc
							(start -0.2794 0.1778)
							(mid -0.249642 0.249642)
							(end -0.1778 0.2794)
						)
						(arc
							(start 0.1778 0.2794)
							(mid 0.249642 0.249642)
							(end 0.2794 0.1778)
						)
						(arc
							(start 0.2794 -0.1778)
							(mid 0.249642 -0.249642)
							(end 0.1778 -0.2794)
						)
					)
					(width 0)
					(fill yes)
				)
			)
		)
	)
	(footprint ""
		(layer "F.Cu")
		(at 329.184 -82.423 -90)
		(property "Reference" "JP1"
			(at 0 0 270)
			(layer "F.SilkS")
			(hide yes)
			(effects
				(font
					(size 1.27 1.27)
				)
			)
		)
		(property "Value" "FCI-CON2-S-GP"
			(at 0 -4.2672 270)
			(unlocked yes)
			(layer "F.Fab")
			(hide yes)
			(effects
				(font
					(size 1.016 1.016)
					(thickness 0.1524)
				)
			)
		)
		(property "Device Type" "680001-202HLF"
			(at 0 -5.7912 270)
			(unlocked yes)
			(layer "F.Fab")
			(hide yes)
			(effects
				(font
					(size 1.016 1.016)
					(thickness 0.1524)
				)
			)
		)
		(duplicate_pad_numbers_are_jumpers no)
		(fp_line
			(start -2.794 1.4732)
			(end -2.794 -1.4478)
			(stroke
				(width 0.1524)
				(type default)
			)
			(layer "F.SilkS")
		)
		(fp_line
			(start 2.794 1.4732)
			(end -2.794 1.4732)
			(stroke
				(width 0.1524)
				(type default)
			)
			(layer "F.SilkS")
		)
		(fp_line
			(start -3.0734 -0.7112)
			(end -3.0734 -1.7272)
			(stroke
				(width 0.4064)
				(type default)
			)
			(layer "F.SilkS")
		)
		(fp_line
			(start -2.794 -1.4478)
			(end 2.794 -1.4478)
			(stroke
				(width 0.1524)
				(type default)
			)
			(layer "F.SilkS")
		)
		(fp_line
			(start 2.794 -1.4478)
			(end 2.794 1.4732)
			(stroke
				(width 0.1524)
				(type default)
			)
			(layer "F.SilkS")
		)
		(fp_line
			(start -3.0734 -1.7272)
			(end -2.0574 -1.7272)
			(stroke
				(width 0.4064)
				(type default)
			)
			(layer "F.SilkS")
		)
		(fp_circle
			(center -1.27 0)
			(end -1.27 -1.0668)
			(stroke
				(width 0.3048)
				(type default)
			)
			(fill no)
			(layer "F.SilkS")
		)
		(fp_circle
			(center 1.27 0)
			(end 1.27 -1.0668)
			(stroke
				(width 0.3048)
				(type default)
			)
			(fill no)
			(layer "F.SilkS")
		)
		(fp_rect
			(start -2.54 1.2192)
			(end 2.54 -1.1938)
			(stroke
				(width 0)
				(type default)
			)
			(fill no)
			(layer "F.CrtYd")
		)
		(fp_poly
			(pts
				(xy -3.048 1.7272) (xy -3.048 0.01524) (xy -2.54 0.01524) (xy -2.54 1.2192) (xy 2.54 1.2192) (xy 2.54 -1.1938)
				(xy -2.54 -1.1938) (xy -2.54 0.01016) (xy -3.048 0.01016) (xy -3.048 -1.7018) (xy 3.048 -1.7018)
				(xy 3.048 1.7272)
			)
			(stroke
				(width 0)
				(type default)
			)
			(fill no)
			(layer "F.CrtYd")
		)
		(fp_rect
			(start -3.048 1.7272)
			(end 3.048 -1.7018)
			(stroke
				(width 0)
				(type default)
			)
			(fill no)
			(layer "F.Fab")
		)
		(pad "1" thru_hole circle
			(at -1.27 0 270)
			(size 1.4224 1.4224)
			(drill 1.016)
			(layers "*.Cu" "*.Mask")
			(remove_unused_layers no)
			(net "ROMA0")
			(clearance 0.1524)
			(thermal_gap 0.1524)
		)
		(pad "2" thru_hole circle
			(at 1.27 0 270)
			(size 1.4224 1.4224)
			(drill 1.016)
			(layers "*.Cu" "*.Mask")
			(remove_unused_layers no)
			(net "AS_ROMA0_R")
			(clearance 0.1524)
			(thermal_gap 0.1524)
		)
	)
	(footprint ""
		(layer "F.Cu")
		(at 269.748 -54.61 90)
		(property "Reference" "PR131"
			(at 0 0 90)
			(layer "F.SilkS")
			(hide yes)
			(effects
				(font
					(size 1.27 1.27)
				)
			)
		)
		(property "Value" "0R2J-2-GP"
			(at 0.064008 -3.993896 90)
			(unlocked yes)
			(layer "F.Fab")
			(hide yes)
			(effects
				(font
					(size 1.016 1.016)
					(thickness 0.1524)
				)
			)
		)
		(property "Device Type" "R402H16"
			(at 0.064008 -5.517896 90)
			(unlocked yes)
			(layer "F.Fab")
			(hide yes)
			(effects
				(font
					(size 1.016 1.016)
					(thickness 0.1524)
				)
			)
		)
		(duplicate_pad_numbers_are_jumpers no)
		(fp_line
			(start 0.508 -0.9398)
			(end -0.508 -0.9398)
			(stroke
				(width 0.1524)
				(type default)
			)
			(layer "F.SilkS")
		)
		(fp_line
			(start -0.508 -0.9398)
			(end -0.508 0.9398)
			(stroke
				(width 0.1524)
				(type default)
			)
			(layer "F.SilkS")
		)
		(fp_rect
			(start -0.508 0.9398)
			(end 0.508 -0.9398)
			(stroke
				(width 0)
				(type default)
			)
			(fill no)
			(layer "F.CrtYd")
		)
		(fp_rect
			(start -0.508 0.9398)
			(end 0.508 -0.9398)
			(stroke
				(width 0)
				(type default)
			)
			(fill no)
			(layer "F.Fab")
		)
		(pad "1" smd custom
			(at 0 -0.4445 90)
			(size 0.1397 0.1397)
			(layers "F.Cu" "F.Mask" "F.Paste")
			(net "BMC_EN_P3V3")
			(options
				(clearance outline)
				(anchor circle)
			)
			(primitives
				(gr_poly
					(pts
						(arc
							(start -0.1778 -0.2794)
							(mid -0.249642 -0.249642)
							(end -0.2794 -0.1778)
						)
						(arc
							(start -0.2794 0.1778)
							(mid -0.249642 0.249642)
							(end -0.1778 0.2794)
						)
						(arc
							(start 0.1778 0.2794)
							(mid 0.249642 0.249642)
							(end 0.2794 0.1778)
						)
						(arc
							(start 0.2794 -0.1778)
							(mid 0.249642 -0.249642)
							(end 0.1778 -0.2794)
						)
					)
					(width 0)
					(fill yes)
				)
			)
		)
		(pad "2" smd custom
			(at 0 0.4445 90)
			(size 0.1397 0.1397)
			(layers "F.Cu" "F.Mask" "F.Paste")
			(net "P3V3_EN_B")
			(options
				(clearance outline)
				(anchor circle)
			)
			(primitives
				(gr_poly
					(pts
						(arc
							(start -0.1778 -0.2794)
							(mid -0.249642 -0.249642)
							(end -0.2794 -0.1778)
						)
						(arc
							(start -0.2794 0.1778)
							(mid -0.249642 0.249642)
							(end -0.1778 0.2794)
						)
						(arc
							(start 0.1778 0.2794)
							(mid 0.249642 0.249642)
							(end 0.2794 0.1778)
						)
						(arc
							(start 0.2794 -0.1778)
							(mid 0.249642 -0.249642)
							(end 0.1778 -0.2794)
						)
					)
					(width 0)
					(fill yes)
				)
			)
		)
	)
	(footprint ""
		(layer "F.Cu")
		(at 215.773 -110.363)
		(property "Reference" "PC147"
			(at 0 0 0)
			(layer "F.SilkS")
			(hide yes)
			(effects
				(font
					(size 1.27 1.27)
				)
			)
		)
		(property "Value" "SC470P50V2KX-3GP"
			(at 1.1811 -2.7051 0)
			(unlocked yes)
			(layer "F.Fab")
			(hide yes)
			(effects
				(font
					(size 1.016 1.016)
					(thickness 0.1524)
				)
			)
		)
		(property "Device Type" "C402H22"
			(at 1.1811 -4.2291 0)
			(unlocked yes)
			(layer "F.Fab")
			(hide yes)
			(effects
				(font
					(size 1.016 1.016)
					(thickness 0.1524)
				)
			)
		)
		(duplicate_pad_numbers_are_jumpers no)
		(fp_rect
			(start -0.4318 0.9525)
			(end 0.4318 -0.9525)
			(stroke
				(width 0)
				(type default)
			)
			(fill no)
			(layer "F.CrtYd")
		)
		(fp_rect
			(start -0.4318 0.9525)
			(end 0.4318 -0.9525)
			(stroke
				(width 0)
				(type default)
			)
			(fill no)
			(layer "F.Fab")
		)
		(pad "1" smd custom
			(at 0 -0.4445)
			(size 0.1524 0.1524)
			(layers "F.Cu" "F.Mask" "F.Paste")
			(net "GND")
			(options
				(clearance outline)
				(anchor circle)
			)
			(primitives
				(gr_poly
					(pts
						(arc
							(start 0.3048 -0.2032)
							(mid 0.275042 -0.275042)
							(end 0.2032 -0.3048)
						)
						(arc
							(start -0.2032 -0.3048)
							(mid -0.275042 -0.275042)
							(end -0.3048 -0.2032)
						)
						(arc
							(start -0.3048 0.2032)
							(mid -0.275042 0.275042)
							(end -0.2032 0.3048)
						)
						(arc
							(start 0.2032 0.3048)
							(mid 0.275042 0.275042)
							(end 0.3048 0.2032)
						)
					)
					(width 0)
					(fill yes)
				)
			)
		)
		(pad "2" smd custom
			(at 0 0.4445)
			(size 0.1524 0.1524)
			(layers "F.Cu" "F.Mask" "F.Paste")
			(net "TPS74801_1V5_C_SS")
			(options
				(clearance outline)
				(anchor circle)
			)
			(primitives
				(gr_poly
					(pts
						(arc
							(start 0.3048 -0.2032)
							(mid 0.275042 -0.275042)
							(end 0.2032 -0.3048)
						)
						(arc
							(start -0.2032 -0.3048)
							(mid -0.275042 -0.275042)
							(end -0.3048 -0.2032)
						)
						(arc
							(start -0.3048 0.2032)
							(mid -0.275042 0.275042)
							(end -0.2032 0.3048)
						)
						(arc
							(start 0.2032 0.3048)
							(mid 0.275042 0.275042)
							(end 0.3048 0.2032)
						)
					)
					(width 0)
					(fill yes)
				)
			)
		)
	)
	(footprint ""
		(layer "F.Cu")
		(at 87.122 -17.907)
		(property "Reference" "PC193"
			(at 0 0 0)
			(layer "F.SilkS")
			(hide yes)
			(effects
				(font
					(size 1.27 1.27)
				)
			)
		)
		(property "Value" "SC1U50V3KX-GP"
			(at 0 -2.8194 0)
			(unlocked yes)
			(layer "F.Fab")
			(hide yes)
			(effects
				(font
					(size 1.016 1.016)
					(thickness 0.1524)
				)
			)
		)
		(property "Device Type" "C603H32"
			(at 0 -4.3434 0)
			(unlocked yes)
			(layer "F.Fab")
			(hide yes)
			(effects
				(font
					(size 1.016 1.016)
					(thickness 0.1524)
				)
			)
		)
		(duplicate_pad_numbers_are_jumpers no)
		(fp_line
			(start 0.508 0)
			(end -0.508 0)
			(stroke
				(width 0.2032)
				(type default)
			)
			(layer "F.SilkS")
		)
		(fp_rect
			(start -0.5842 1.3335)
			(end 0.5842 -1.3335)
			(stroke
				(width 0)
				(type default)
			)
			(fill no)
			(layer "F.CrtYd")
		)
		(fp_rect
			(start -0.5842 1.3335)
			(end 0.5842 -1.3335)
			(stroke
				(width 0)
				(type default)
			)
			(fill no)
			(layer "F.Fab")
		)
		(pad "1" smd custom
			(at 0 -0.762)
			(size 0.2159 0.2159)
			(layers "F.Cu" "F.Mask" "F.Paste")
			(net "VT235_BST")
			(options
				(clearance outline)
				(anchor circle)
			)
			(primitives
				(gr_poly
					(pts
						(arc
							(start -0.3302 -0.4318)
							(mid -0.402042 -0.402042)
							(end -0.4318 -0.3302)
						)
						(arc
							(start -0.4318 0.3302)
							(mid -0.402042 0.402042)
							(end -0.3302 0.4318)
						)
						(arc
							(start 0.3302 0.4318)
							(mid 0.402042 0.402042)
							(end 0.4318 0.3302)
						)
						(arc
							(start 0.4318 -0.3302)
							(mid 0.402042 -0.402042)
							(end 0.3302 -0.4318)
						)
					)
					(width 0)
					(fill yes)
				)
			)
		)
		(pad "2" smd custom
			(at 0 0.762)
			(size 0.2159 0.2159)
			(layers "F.Cu" "F.Mask" "F.Paste")
			(net "VT235_VX")
			(options
				(clearance outline)
				(anchor circle)
			)
			(primitives
				(gr_poly
					(pts
						(arc
							(start -0.3302 -0.4318)
							(mid -0.402042 -0.402042)
							(end -0.4318 -0.3302)
						)
						(arc
							(start -0.4318 0.3302)
							(mid -0.402042 0.402042)
							(end -0.3302 0.4318)
						)
						(arc
							(start 0.3302 0.4318)
							(mid 0.402042 0.402042)
							(end 0.4318 0.3302)
						)
						(arc
							(start 0.4318 -0.3302)
							(mid 0.402042 -0.402042)
							(end 0.3302 -0.4318)
						)
					)
					(width 0)
					(fill yes)
				)
			)
		)
	)
)
